(kicad_pcb
	(version 20260206)
	(generator "pcbnew")
	(generator_version "10.0")
	(general
		(thickness 1.6)
		(legacy_teardrops no)
	)
	(paper "A4")
	(title_block
		(title "v2-pdb — ms_pdb_v2.brd")
		(comment 1 "Open CloudServer (Microsoft) / footprints 57-65 of 348")
	)
	(layers
		(0 "F.Cu" signal "TOP")
		(4 "In1.Cu" signal "GND")
		(6 "In2.Cu" signal "IN1")
		(8 "In3.Cu" signal "VCC")
		(10 "In4.Cu" signal "VCC1")
		(12 "In5.Cu" signal "IN2")
		(14 "In6.Cu" signal "GND1")
		(2 "B.Cu" signal "BOTTOM")
		(9 "F.Adhes" user "F.Adhesive")
		(11 "B.Adhes" user "B.Adhesive")
		(13 "F.Paste" user "Package Geometry/Pastemask Top")
		(15 "B.Paste" user "Package Geometry/Pastemask Bottom")
		(5 "F.SilkS" user "Ref Des/Silkscreen Top")
		(7 "B.SilkS" user "Ref Des/Silkscreen Bottom")
		(1 "F.Mask" user "Board Geometry/Soldermask Top")
		(3 "B.Mask" user "Board Geometry/Soldermask Bottom")
		(17 "Dwgs.User" user "User.Drawings")
		(19 "Cmts.User" user "User.Comments")
		(21 "Eco1.User" user "User.Eco1")
		(23 "Eco2.User" user "User.Eco2")
		(25 "Edge.Cuts" user "Board Geometry/Outline")
		(27 "Margin" user)
		(31 "F.CrtYd" user "Package Geometry/Place Bound Top")
		(29 "B.CrtYd" user "Package Geometry/Place Bound Bottom")
		(35 "F.Fab" user "Ref Des/Assembly Top")
		(33 "B.Fab" user "Ref Des/Assembly Bottom")
	)
	(footprint ""
		(layer "F.Cu")
		(at 26.102056 -276.12213)
		(property "Reference" "R75"
			(at -4.037838 -0.005334 0)
			(unlocked yes)
			(layer "F.SilkS")
			(effects
				(font
					(size 0.7874 0.5842)
					(thickness 0.1524)
				)
				(justify left)
			)
		)
		(property "Value" ""
			(at 0 0 0)
			(layer "F.Fab")
			(effects
				(font
					(size 1.27 1.27)
				)
			)
		)
		(duplicate_pad_numbers_are_jumpers no)
		(fp_line
			(start -0.7874 -0.4064)
			(end 0.7874 -0.4064)
			(stroke
				(width 0.1524)
				(type default)
			)
			(layer "F.SilkS")
		)
		(fp_line
			(start -0.7874 0.4064)
			(end -0.7874 -0.4064)
			(stroke
				(width 0.1524)
				(type default)
			)
			(layer "F.SilkS")
		)
		(fp_line
			(start 0.7874 -0.4064)
			(end 0.7874 0.4064)
			(stroke
				(width 0.1524)
				(type default)
			)
			(layer "F.SilkS")
		)
		(fp_line
			(start 0.7874 0.4064)
			(end -0.7874 0.4064)
			(stroke
				(width 0.1524)
				(type default)
			)
			(layer "F.SilkS")
		)
		(fp_poly
			(pts
				(xy -0.508 0.2794) (xy -0.508 0.2286) (xy -0.635 0.2286) (xy -0.635 -0.254) (xy -0.5334 -0.254)
				(xy -0.5334 -0.2794) (xy 0.5334 -0.2794) (xy 0.5334 -0.254) (xy 0.635 -0.254) (xy 0.635 0.254) (xy 0.5334 0.254)
				(xy 0.5334 0.2794)
			)
			(stroke
				(width 0)
				(type default)
			)
			(fill no)
			(layer "F.CrtYd")
		)
		(pad "1" smd rect
			(at 0.40005 0)
			(size 0.4572 0.508)
			(layers "F.Cu" "F.Mask" "F.Paste")
			(net "PSU4_PS_KILL")
		)
		(pad "2" smd rect
			(at -0.40005 0)
			(size 0.4572 0.508)
			(layers "F.Cu" "F.Mask" "F.Paste")
			(net "GND")
		)
	)
	(footprint ""
		(layer "F.Cu")
		(at 49.949354 -107.119928 180)
		(property "Reference" "CE5"
			(at -5.215128 0.67437 0)
			(unlocked yes)
			(layer "F.SilkS")
			(effects
				(font
					(size 0.7874 0.5842)
					(thickness 0.1524)
				)
				(justify left)
			)
		)
		(property "Value" ""
			(at 0 0 180)
			(layer "F.Fab")
			(effects
				(font
					(size 1.27 1.27)
				)
			)
		)
		(duplicate_pad_numbers_are_jumpers no)
		(fp_line
			(start 0 -4.2672)
			(end 0 4.2672)
			(stroke
				(width 0.1524)
				(type default)
			)
			(layer "F.SilkS")
		)
		(fp_circle
			(center 0 0)
			(end -4.2672 0)
			(stroke
				(width 0.1524)
				(type default)
			)
			(fill no)
			(layer "F.SilkS")
		)
		(fp_poly
			(pts
				(arc
					(start 0 -4.2672)
					(mid 4.2672 0)
					(end 0 4.2672)
				)
			)
			(stroke
				(width 0)
				(type default)
			)
			(fill yes)
			(layer "F.SilkS")
		)
		(fp_poly
			(pts
				(xy -2.5146 -0.762) (xy -0.9906 -0.762) (xy -0.9906 0.762) (xy -2.5146 0.762)
			)
			(stroke
				(width 0)
				(type default)
			)
			(fill no)
			(layer "B.CrtYd")
		)
		(fp_poly
			(pts
				(arc
					(start 1.7526 0.762)
					(mid 2.291415 -0.538815)
					(end 0.9906 0)
				)
				(arc
					(start 0.9906 0.0254)
					(mid 1.206345 0.546255)
					(end 1.7272 0.762)
				)
			)
			(stroke
				(width 0)
				(type default)
			)
			(fill no)
			(layer "B.CrtYd")
		)
		(fp_poly
			(pts
				(arc
					(start -4.2672 0)
					(mid 4.2672 0)
					(end -4.2672 0)
				)
			)
			(stroke
				(width 0)
				(type default)
			)
			(fill no)
			(layer "F.CrtYd")
		)
		(fp_circle
			(center 0 0)
			(end -4.2672 0)
			(stroke
				(width 0.1)
				(type default)
			)
			(fill no)
			(layer "F.Fab")
		)
		(fp_text user "+"
			(at -6.30936 -1.69926 180)
			(unlocked yes)
			(layer "F.SilkS")
			(effects
				(font
					(size 1.905 1.4224)
					(thickness 0.1524)
				)
				(justify left)
			)
		)
		(fp_text user "+"
			(at -5.6642 -0.34925 180)
			(unlocked yes)
			(layer "F.Fab")
			(effects
				(font
					(size 1.905 1.4224)
					(thickness 0.000001)
				)
				(justify left)
			)
		)
		(pad "1" thru_hole rect
			(at -1.75006 0 180)
			(size 1.397 1.397)
			(drill 0.9144)
			(layers "*.Cu" "*.Mask")
			(remove_unused_layers no)
			(net "P12V")
			(clearance 0.0127)
			(thermal_gap 0.0127)
			(padstack
				(mode front_inner_back)
				(layer "Inner"
					(shape circle)
					(size 1.397 1.397)
					(clearance 0.0127)
				)
				(layer "B.Cu"
					(shape rect)
					(size 1.397 1.397)
					(clearance 0.0127)
				)
			)
		)
		(pad "2" thru_hole circle
			(at 1.75006 0 180)
			(size 1.397 1.397)
			(drill 0.9144)
			(layers "*.Cu" "*.Mask")
			(remove_unused_layers no)
			(net "GND")
			(clearance 0.0127)
			(thermal_gap 0.0127)
		)
	)
	(footprint ""
		(layer "F.Cu")
		(at 73.687178 -259.450078 90)
		(property "Reference" "C47"
			(at -4.374134 0.10795 90)
			(unlocked yes)
			(layer "F.SilkS")
			(effects
				(font
					(size 0.7874 0.5842)
					(thickness 0.1524)
				)
				(justify left)
			)
		)
		(property "Value" ""
			(at 0 0 90)
			(layer "F.Fab")
			(effects
				(font
					(size 1.27 1.27)
				)
			)
		)
		(duplicate_pad_numbers_are_jumpers no)
		(fp_line
			(start 0.7874 -0.4064)
			(end 0.7874 0.4064)
			(stroke
				(width 0.1524)
				(type default)
			)
			(layer "F.SilkS")
		)
		(fp_line
			(start -0.7874 -0.4064)
			(end 0.7874 -0.4064)
			(stroke
				(width 0.1524)
				(type default)
			)
			(layer "F.SilkS")
		)
		(fp_line
			(start 0 0.381)
			(end 0 -0.381)
			(stroke
				(width 0.1524)
				(type default)
			)
			(layer "F.SilkS")
		)
		(fp_line
			(start 0.7874 0.4064)
			(end -0.7874 0.4064)
			(stroke
				(width 0.1524)
				(type default)
			)
			(layer "F.SilkS")
		)
		(fp_line
			(start -0.7874 0.4064)
			(end -0.7874 -0.4064)
			(stroke
				(width 0.1524)
				(type default)
			)
			(layer "F.SilkS")
		)
		(fp_poly
			(pts
				(xy -0.5334 0.254) (xy -0.635 0.254) (xy -0.635 0.2286) (xy -0.635 -0.254) (xy -0.5334 -0.254) (xy -0.5334 -0.2794)
				(xy 0.5334 -0.2794) (xy 0.5334 -0.254) (xy 0.635 -0.254) (xy 0.635 0.254) (xy 0.5334 0.254) (xy 0.5334 0.2794)
				(xy -0.508 0.2794) (xy -0.5334 0.2794)
			)
			(stroke
				(width 0)
				(type default)
			)
			(fill no)
			(layer "F.CrtYd")
		)
		(pad "1" smd rect
			(at 0.40005 0 90)
			(size 0.4572 0.508)
			(layers "F.Cu" "F.Mask" "F.Paste")
			(net "P12V")
		)
		(pad "2" smd rect
			(at -0.40005 0 90)
			(size 0.4572 0.508)
			(layers "F.Cu" "F.Mask" "F.Paste")
			(net "GND")
		)
	)
	(footprint ""
		(layer "F.Cu")
		(at 91.399868 -64.46012)
		(property "Reference" "H16"
			(at -5.1308 -5.23113 0)
			(unlocked yes)
			(layer "F.SilkS")
			(effects
				(font
					(size 0.7874 0.5842)
					(thickness 0.1524)
				)
				(justify left)
			)
		)
		(property "Value" ""
			(at 0 0 0)
			(layer "F.Fab")
			(effects
				(font
					(size 1.27 1.27)
				)
			)
		)
		(duplicate_pad_numbers_are_jumpers no)
		(fp_circle
			(center 0 0)
			(end 4.826 0)
			(stroke
				(width 0.1524)
				(type default)
			)
			(fill no)
			(layer "F.SilkS")
		)
		(fp_circle
			(center 0 0)
			(end 4.826 0)
			(stroke
				(width 0.1524)
				(type default)
			)
			(fill no)
			(layer "B.SilkS")
		)
		(fp_poly
			(pts
				(arc
					(start 0 4.0132)
					(mid 0 -4.0132)
					(end 0 4.0132)
				)
			)
			(stroke
				(width 0)
				(type default)
			)
			(fill no)
			(layer "F.CrtYd")
		)
		(pad "" np_thru_hole circle
			(at 0 0)
			(size 8.001 8.001)
			(drill 8.001)
			(layers "*.Cu" "*.Mask")
			(clearance 0.381)
			(thermal_gap 0.381)
		)
		(zone
			(layers "F.Cu" "B.Cu" "In1.Cu" "In2.Cu" "In3.Cu" "In4.Cu" "In5.Cu" "In6.Cu")
			(hatch none 0.5)
			(connect_pads
				(clearance 0)
			)
			(min_thickness 0.25)
			(keepout
				(tracks not_allowed)
				(vias allowed)
				(pads allowed)
				(copperpour not_allowed)
				(footprints allowed)
			)
			(placement
				(enabled no)
				(sheetname "")
			)
			(fill
				(thermal_gap 0.5)
				(thermal_bridge_width 0.5)
				(island_removal_mode 0)
			)
			(polygon
				(pts
					(arc
						(start 91.399868 -59.93892)
						(mid 91.399868 -68.98132)
						(end 91.399868 -59.93892)
					)
				)
			)
		)
	)
	(footprint ""
		(layer "F.Cu")
		(at 70.558152 -216.615772 90)
		(property "Reference" "C39"
			(at 1.151128 0.12319 90)
			(unlocked yes)
			(layer "F.SilkS")
			(effects
				(font
					(size 0.7874 0.5842)
					(thickness 0.1524)
				)
				(justify left)
			)
		)
		(property "Value" ""
			(at 0 0 90)
			(layer "F.Fab")
			(effects
				(font
					(size 1.27 1.27)
				)
			)
		)
		(duplicate_pad_numbers_are_jumpers no)
		(fp_line
			(start 0.7874 -0.4064)
			(end 0.7874 0.4064)
			(stroke
				(width 0.1524)
				(type default)
			)
			(layer "F.SilkS")
		)
		(fp_line
			(start -0.7874 -0.4064)
			(end 0.7874 -0.4064)
			(stroke
				(width 0.1524)
				(type default)
			)
			(layer "F.SilkS")
		)
		(fp_line
			(start 0 0.381)
			(end 0 -0.381)
			(stroke
				(width 0.1524)
				(type default)
			)
			(layer "F.SilkS")
		)
		(fp_line
			(start 0.7874 0.4064)
			(end -0.7874 0.4064)
			(stroke
				(width 0.1524)
				(type default)
			)
			(layer "F.SilkS")
		)
		(fp_line
			(start -0.7874 0.4064)
			(end -0.7874 -0.4064)
			(stroke
				(width 0.1524)
				(type default)
			)
			(layer "F.SilkS")
		)
		(fp_poly
			(pts
				(xy -0.5334 0.254) (xy -0.635 0.254) (xy -0.635 0.2286) (xy -0.635 -0.254) (xy -0.5334 -0.254) (xy -0.5334 -0.2794)
				(xy 0.5334 -0.2794) (xy 0.5334 -0.254) (xy 0.635 -0.254) (xy 0.635 0.254) (xy 0.5334 0.254) (xy 0.5334 0.2794)
				(xy -0.508 0.2794) (xy -0.5334 0.2794)
			)
			(stroke
				(width 0)
				(type default)
			)
			(fill no)
			(layer "F.CrtYd")
		)
		(pad "1" smd rect
			(at 0.40005 0 90)
			(size 0.4572 0.508)
			(layers "F.Cu" "F.Mask" "F.Paste")
			(net "P12V")
		)
		(pad "2" smd rect
			(at -0.40005 0 90)
			(size 0.4572 0.508)
			(layers "F.Cu" "F.Mask" "F.Paste")
			(net "GND")
		)
	)
	(footprint ""
		(layer "F.Cu")
		(at 13.265658 -340.460838 -90)
		(property "Reference" "R41"
			(at -1.347724 -0.199136 90)
			(unlocked yes)
			(layer "F.SilkS")
			(effects
				(font
					(size 0.7874 0.5842)
					(thickness 0.1524)
				)
				(justify left)
			)
		)
		(property "Value" ""
			(at 0 0 270)
			(layer "F.Fab")
			(effects
				(font
					(size 1.27 1.27)
				)
			)
		)
		(duplicate_pad_numbers_are_jumpers no)
		(fp_line
			(start -0.7874 0.4064)
			(end -0.7874 -0.4064)
			(stroke
				(width 0.1524)
				(type default)
			)
			(layer "F.SilkS")
		)
		(fp_line
			(start 0.7874 0.4064)
			(end -0.7874 0.4064)
			(stroke
				(width 0.1524)
				(type default)
			)
			(layer "F.SilkS")
		)
		(fp_line
			(start -0.7874 -0.4064)
			(end 0.7874 -0.4064)
			(stroke
				(width 0.1524)
				(type default)
			)
			(layer "F.SilkS")
		)
		(fp_line
			(start 0.7874 -0.4064)
			(end 0.7874 0.4064)
			(stroke
				(width 0.1524)
				(type default)
			)
			(layer "F.SilkS")
		)
		(fp_poly
			(pts
				(xy -0.508 0.2794) (xy -0.508 0.2286) (xy -0.635 0.2286) (xy -0.635 -0.254) (xy -0.5334 -0.254)
				(xy -0.5334 -0.2794) (xy 0.5334 -0.2794) (xy 0.5334 -0.254) (xy 0.635 -0.254) (xy 0.635 0.254) (xy 0.5334 0.254)
				(xy 0.5334 0.2794)
			)
			(stroke
				(width 0)
				(type default)
			)
			(fill no)
			(layer "F.CrtYd")
		)
		(pad "1" smd rect
			(at 0.40005 0 270)
			(size 0.4572 0.508)
			(layers "F.Cu" "F.Mask" "F.Paste")
			(net "P3V3")
		)
		(pad "2" smd rect
			(at -0.40005 0 270)
			(size 0.4572 0.508)
			(layers "F.Cu" "F.Mask" "F.Paste")
			(net "FRU_WP")
		)
	)
	(footprint ""
		(layer "F.Cu")
		(at 39.51478 -464.77047 -90)
		(property "Reference" "R98"
			(at -1.157224 -0.122428 90)
			(unlocked yes)
			(layer "F.SilkS")
			(effects
				(font
					(size 0.7874 0.5842)
					(thickness 0.1524)
				)
				(justify left)
			)
		)
		(property "Value" ""
			(at 0 0 270)
			(layer "F.Fab")
			(effects
				(font
					(size 1.27 1.27)
				)
			)
		)
		(duplicate_pad_numbers_are_jumpers no)
		(fp_line
			(start -0.7874 0.4064)
			(end -0.7874 -0.4064)
			(stroke
				(width 0.1524)
				(type default)
			)
			(layer "F.SilkS")
		)
		(fp_line
			(start 0.7874 0.4064)
			(end -0.7874 0.4064)
			(stroke
				(width 0.1524)
				(type default)
			)
			(layer "F.SilkS")
		)
		(fp_line
			(start -0.7874 -0.4064)
			(end 0.7874 -0.4064)
			(stroke
				(width 0.1524)
				(type default)
			)
			(layer "F.SilkS")
		)
		(fp_line
			(start 0.7874 -0.4064)
			(end 0.7874 0.4064)
			(stroke
				(width 0.1524)
				(type default)
			)
			(layer "F.SilkS")
		)
		(fp_poly
			(pts
				(xy -0.508 0.2794) (xy -0.508 0.2286) (xy -0.635 0.2286) (xy -0.635 -0.254) (xy -0.5334 -0.254)
				(xy -0.5334 -0.2794) (xy 0.5334 -0.2794) (xy 0.5334 -0.254) (xy 0.635 -0.254) (xy 0.635 0.254) (xy 0.5334 0.254)
				(xy 0.5334 0.2794)
			)
			(stroke
				(width 0)
				(type default)
			)
			(fill no)
			(layer "F.CrtYd")
		)
		(pad "1" smd rect
			(at 0.40005 0 270)
			(size 0.4572 0.508)
			(layers "F.Cu" "F.Mask" "F.Paste")
			(net "PSU6_REMOTE_P")
		)
		(pad "2" smd rect
			(at -0.40005 0 270)
			(size 0.4572 0.508)
			(layers "F.Cu" "F.Mask" "F.Paste")
			(net "PSU6_REMOTE_R_P")
		)
	)
	(footprint ""
		(layer "F.Cu")
		(at 39.874952 -461.170274 180)
		(property "Reference" "R23"
			(at -1.982978 -0.229108 0)
			(unlocked yes)
			(layer "F.SilkS")
			(effects
				(font
					(size 0.7874 0.5842)
					(thickness 0.1524)
				)
				(justify left)
			)
		)
		(property "Value" ""
			(at 0 0 180)
			(layer "F.Fab")
			(effects
				(font
					(size 1.27 1.27)
				)
			)
		)
		(duplicate_pad_numbers_are_jumpers no)
		(fp_line
			(start 0.7874 0.4064)
			(end -0.7874 0.4064)
			(stroke
				(width 0.1524)
				(type default)
			)
			(layer "F.SilkS")
		)
		(fp_line
			(start 0.7874 -0.4064)
			(end 0.7874 0.4064)
			(stroke
				(width 0.1524)
				(type default)
			)
			(layer "F.SilkS")
		)
		(fp_line
			(start -0.7874 0.4064)
			(end -0.7874 -0.4064)
			(stroke
				(width 0.1524)
				(type default)
			)
			(layer "F.SilkS")
		)
		(fp_line
			(start -0.7874 -0.4064)
			(end 0.7874 -0.4064)
			(stroke
				(width 0.1524)
				(type default)
			)
			(layer "F.SilkS")
		)
		(fp_poly
			(pts
				(xy -0.508 0.2794) (xy -0.508 0.2286) (xy -0.635 0.2286) (xy -0.635 -0.254) (xy -0.5334 -0.254)
				(xy -0.5334 -0.2794) (xy 0.5334 -0.2794) (xy 0.5334 -0.254) (xy 0.635 -0.254) (xy 0.635 0.254) (xy 0.5334 0.254)
				(xy 0.5334 0.2794)
			)
			(stroke
				(width 0)
				(type default)
			)
			(fill no)
			(layer "F.CrtYd")
		)
		(pad "1" smd rect
			(at 0.40005 0 180)
			(size 0.4572 0.508)
			(layers "F.Cu" "F.Mask" "F.Paste")
			(net "PSU6_AD0")
		)
		(pad "2" smd rect
			(at -0.40005 0 180)
			(size 0.4572 0.508)
			(layers "F.Cu" "F.Mask" "F.Paste")
			(net "GND")
		)
	)
	(footprint ""
		(layer "F.Cu")
		(at 50.350928 -306.383182 180)
		(property "Reference" "CE14"
			(at 8.029448 2.021078 0)
			(unlocked yes)
			(layer "F.SilkS")
			(effects
				(font
					(size 0.7874 0.5842)
					(thickness 0.1524)
				)
				(justify left)
			)
		)
		(property "Value" ""
			(at 0 0 180)
			(layer "F.Fab")
			(effects
				(font
					(size 1.27 1.27)
				)
			)
		)
		(duplicate_pad_numbers_are_jumpers no)
		(fp_line
			(start 0 -4.2672)
			(end 0 4.2672)
			(stroke
				(width 0.1524)
				(type default)
			)
			(layer "F.SilkS")
		)
		(fp_circle
			(center 0 0)
			(end -4.2672 0)
			(stroke
				(width 0.1524)
				(type default)
			)
			(fill no)
			(layer "F.SilkS")
		)
		(fp_poly
			(pts
				(arc
					(start 0 -4.2672)
					(mid 4.2672 0)
					(end 0 4.2672)
				)
			)
			(stroke
				(width 0)
				(type default)
			)
			(fill yes)
			(layer "F.SilkS")
		)
		(fp_poly
			(pts
				(xy -2.5146 -0.762) (xy -0.9906 -0.762) (xy -0.9906 0.762) (xy -2.5146 0.762)
			)
			(stroke
				(width 0)
				(type default)
			)
			(fill no)
			(layer "B.CrtYd")
		)
		(fp_poly
			(pts
				(arc
					(start 1.7526 0.762)
					(mid 2.291415 -0.538815)
					(end 0.9906 0)
				)
				(arc
					(start 0.9906 0.0254)
					(mid 1.206345 0.546255)
					(end 1.7272 0.762)
				)
			)
			(stroke
				(width 0)
				(type default)
			)
			(fill no)
			(layer "B.CrtYd")
		)
		(fp_poly
			(pts
				(arc
					(start -4.2672 0)
					(mid 4.2672 0)
					(end -4.2672 0)
				)
			)
			(stroke
				(width 0)
				(type default)
			)
			(fill no)
			(layer "F.CrtYd")
		)
		(fp_circle
			(center 0 0)
			(end -4.2672 0)
			(stroke
				(width 0.1)
				(type default)
			)
			(fill no)
			(layer "F.Fab")
		)
		(fp_text user "+"
			(at -5.6642 -0.34925 180)
			(unlocked yes)
			(layer "F.SilkS")
			(effects
				(font
					(size 1.905 1.4224)
					(thickness 0.1524)
				)
				(justify left)
			)
		)
		(fp_text user "+"
			(at -5.6642 -0.34925 180)
			(unlocked yes)
			(layer "F.Fab")
			(effects
				(font
					(size 1.905 1.4224)
					(thickness 0.000001)
				)
				(justify left)
			)
		)
		(pad "1" thru_hole rect
			(at -1.75006 0 180)
			(size 1.397 1.397)
			(drill 0.9144)
			(layers "*.Cu" "*.Mask")
			(remove_unused_layers no)
			(net "P12V")
			(clearance 0.0127)
			(thermal_gap 0.0127)
			(padstack
				(mode front_inner_back)
				(layer "Inner"
					(shape circle)
					(size 1.397 1.397)
					(clearance 0.0127)
				)
				(layer "B.Cu"
					(shape rect)
					(size 1.397 1.397)
					(clearance 0.0127)
				)
			)
		)
		(pad "2" thru_hole circle
			(at 1.75006 0 180)
			(size 1.397 1.397)
			(drill 0.9144)
			(layers "*.Cu" "*.Mask")
			(remove_unused_layers no)
			(net "GND")
			(clearance 0.0127)
			(thermal_gap 0.0127)
		)
	)
)
